(kicad_pcb
	(version 20260206)
	(generator "pcbnew")
	(generator_version "10.0")
	(general
		(thickness 1.6)
		(legacy_teardrops no)
	)
	(paper "A4")
	(title_block
		(title "03242023_DA0F0TMBIJ0_F0T_Motherboard_J_brd_V01_OCP.brd")
		(comment 1 "Grand Teton / footprints 4367-4372 of 6105")
	)
	(layers
		(0 "F.Cu" signal "TOP")
		(4 "In1.Cu" signal "GND")
		(6 "In2.Cu" signal "IN1")
		(8 "In3.Cu" signal "GND1")
		(10 "In4.Cu" signal "IN2")
		(12 "In5.Cu" signal "GND2")
		(14 "In6.Cu" signal "IN3")
		(16 "In7.Cu" signal "GND3")
		(18 "In8.Cu" signal "VCC")
		(20 "In9.Cu" signal "VCC1")
		(22 "In10.Cu" signal "GND4")
		(24 "In11.Cu" signal "IN4")
		(26 "In12.Cu" signal "GND5")
		(28 "In13.Cu" signal "IN5")
		(30 "In14.Cu" signal "GND6")
		(32 "In15.Cu" signal "IN6")
		(34 "In16.Cu" signal "GND7")
		(2 "B.Cu" signal "BOTTOM")
		(9 "F.Adhes" user "F.Adhesive")
		(11 "B.Adhes" user "B.Adhesive")
		(13 "F.Paste" user "Package Geometry/Pastemask Top")
		(15 "B.Paste" user "Package Geometry/Pastemask Bottom")
		(5 "F.SilkS" user "Ref Des/Silkscreen Top")
		(7 "B.SilkS" user "Ref Des/Silkscreen Bottom")
		(1 "F.Mask" user "Board Geometry/Soldermask Top")
		(3 "B.Mask" user "Board Geometry/Soldermask Bottom")
		(17 "Dwgs.User" user "User.Drawings")
		(19 "Cmts.User" user "User.Comments")
		(21 "Eco1.User" user "User.Eco1")
		(23 "Eco2.User" user "User.Eco2")
		(25 "Edge.Cuts" user "Board Geometry/Outline")
		(27 "Margin" user)
		(31 "F.CrtYd" user "Package Geometry/Place Bound Top")
		(29 "B.CrtYd" user "Package Geometry/Place Bound Bottom")
		(35 "F.Fab" user "Ref Des/Assembly Top")
		(33 "B.Fab" user "Ref Des/Assembly Bottom")
	)
	(footprint ""
		(layer "B.Cu")
		(at 373.546624 -190.703454 90)
		(property "Reference" "R960"
			(at 0 0 90)
			(layer "B.SilkS")
			(hide yes)
			(effects
				(font
					(size 1.27 1.27)
				)
				(justify mirror)
			)
		)
		(property "Value" ""
			(at 0 0 90)
			(layer "B.Fab")
			(effects
				(font
					(size 1.27 1.27)
				)
				(justify mirror)
			)
		)
		(duplicate_pad_numbers_are_jumpers no)
		(fp_line
			(start 0.7874 -0.4064)
			(end -0.7874 -0.4064)
			(stroke
				(width 0.1524)
				(type default)
			)
			(layer "B.SilkS")
		)
		(fp_line
			(start -0.7874 -0.4064)
			(end -0.7874 0.4064)
			(stroke
				(width 0.1524)
				(type default)
			)
			(layer "B.SilkS")
		)
		(fp_line
			(start 0.7874 0.4064)
			(end 0.7874 -0.4064)
			(stroke
				(width 0.1524)
				(type default)
			)
			(layer "B.SilkS")
		)
		(fp_line
			(start -0.7874 0.4064)
			(end 0.7874 0.4064)
			(stroke
				(width 0.1524)
				(type default)
			)
			(layer "B.SilkS")
		)
		(fp_line
			(start 0.67945 -0.305054)
			(end 0.12065 -0.305054)
			(stroke
				(width 0.1)
				(type default)
			)
			(layer "B.Fab")
		)
		(fp_line
			(start 0.12065 -0.305054)
			(end 0.12065 -0.2794)
			(stroke
				(width 0.1)
				(type default)
			)
			(layer "B.Fab")
		)
		(fp_line
			(start -0.12065 -0.3048)
			(end -0.67945 -0.3048)
			(stroke
				(width 0.1)
				(type default)
			)
			(layer "B.Fab")
		)
		(fp_line
			(start -0.67945 -0.3048)
			(end -0.67945 0.3048)
			(stroke
				(width 0.1)
				(type default)
			)
			(layer "B.Fab")
		)
		(fp_line
			(start 0.12065 -0.2794)
			(end -0.12065 -0.2794)
			(stroke
				(width 0.1)
				(type default)
			)
			(layer "B.Fab")
		)
		(fp_line
			(start -0.12065 -0.2794)
			(end -0.12065 -0.3048)
			(stroke
				(width 0.1)
				(type default)
			)
			(layer "B.Fab")
		)
		(fp_line
			(start 0.12065 0.2794)
			(end 0.12065 0.3048)
			(stroke
				(width 0.1)
				(type default)
			)
			(layer "B.Fab")
		)
		(fp_line
			(start -0.120396 0.2794)
			(end 0.12065 0.2794)
			(stroke
				(width 0.1)
				(type default)
			)
			(layer "B.Fab")
		)
		(fp_line
			(start 0.67945 0.3048)
			(end 0.67945 -0.305054)
			(stroke
				(width 0.1)
				(type default)
			)
			(layer "B.Fab")
		)
		(fp_line
			(start 0.12065 0.3048)
			(end 0.67945 0.3048)
			(stroke
				(width 0.1)
				(type default)
			)
			(layer "B.Fab")
		)
		(fp_line
			(start -0.120396 0.3048)
			(end -0.120396 0.2794)
			(stroke
				(width 0.1)
				(type default)
			)
			(layer "B.Fab")
		)
		(fp_line
			(start -0.67945 0.3048)
			(end -0.120396 0.3048)
			(stroke
				(width 0.1)
				(type default)
			)
			(layer "B.Fab")
		)
		(pad "1" smd circle
			(at 0.40005 0 270)
			(size 0 0)
			(layers "B.Cu" "B.Mask" "B.Paste")
			(net "SMB_PEHPCPU0_GTL_SCL")
		)
		(pad "2" smd circle
			(at -0.40005 0 270)
			(size 0 0)
			(layers "B.Cu" "B.Mask" "B.Paste")
			(net "SMB_PEHPCPU0_GTL_R_SCL")
		)
	)
	(footprint ""
		(layer "B.Cu")
		(at 181.865016 -346.586302 -90)
		(property "Reference" "PC1205"
			(at 0 0 90)
			(layer "B.SilkS")
			(hide yes)
			(effects
				(font
					(size 1.27 1.27)
				)
				(justify mirror)
			)
		)
		(property "Value" ""
			(at 0 0 90)
			(layer "B.Fab")
			(effects
				(font
					(size 1.27 1.27)
				)
				(justify mirror)
			)
		)
		(duplicate_pad_numbers_are_jumpers no)
		(fp_line
			(start -4.533392 2.249932)
			(end 4.533392 2.249932)
			(stroke
				(width 0.1524)
				(type default)
			)
			(layer "B.SilkS")
		)
		(fp_line
			(start 4.533392 2.249932)
			(end 4.533392 -2.249932)
			(stroke
				(width 0.1524)
				(type default)
			)
			(layer "B.SilkS")
		)
		(fp_line
			(start -4.533392 -2.249932)
			(end -4.533392 2.249932)
			(stroke
				(width 0.1524)
				(type default)
			)
			(layer "B.SilkS")
		)
		(fp_line
			(start 4.533392 -2.249932)
			(end -4.533392 -2.249932)
			(stroke
				(width 0.1524)
				(type default)
			)
			(layer "B.SilkS")
		)
		(fp_poly
			(pts
				(xy 4.533392 -2.326132) (xy 5.39242 -2.326132) (xy 5.39242 2.326132) (xy 4.533392 2.326132)
			)
			(stroke
				(width 0)
				(type default)
			)
			(fill yes)
			(layer "B.SilkS")
		)
		(fp_line
			(start -3.750056 2.249932)
			(end 3.750056 2.249932)
			(stroke
				(width 0.1)
				(type default)
			)
			(layer "B.Fab")
		)
		(fp_line
			(start 3.750056 2.249932)
			(end 3.750056 -2.249932)
			(stroke
				(width 0.1)
				(type default)
			)
			(layer "B.Fab")
		)
		(fp_line
			(start -3.750056 -2.249932)
			(end -3.750056 2.249932)
			(stroke
				(width 0.1)
				(type default)
			)
			(layer "B.Fab")
		)
		(fp_line
			(start 3.750056 -2.249932)
			(end -3.750056 -2.249932)
			(stroke
				(width 0.1)
				(type default)
			)
			(layer "B.Fab")
		)
		(fp_text user "+"
			(at 6.322314 0.786384 180)
			(unlocked yes)
			(layer "B.SilkS")
			(effects
				(font
					(size 1.905 1.4224)
					(thickness 0.1524)
				)
				(justify left mirror)
			)
		)
		(fp_text user "-"
			(at -4.8514 -0.14605 270)
			(unlocked yes)
			(layer "B.SilkS")
			(effects
				(font
					(size 1.905 1.4224)
					(thickness 0.1524)
				)
				(justify left mirror)
			)
		)
		(fp_text user "+"
			(at 6.322314 0.786384 180)
			(unlocked yes)
			(layer "B.Fab")
			(effects
				(font
					(size 1.905 1.4224)
					(thickness 0.1524)
				)
				(justify left mirror)
			)
		)
		(fp_text user "-"
			(at -4.8514 -0.14605 270)
			(unlocked yes)
			(layer "B.Fab")
			(effects
				(font
					(size 1.905 1.4224)
					(thickness 0.1524)
				)
				(justify left mirror)
			)
		)
		(pad "1" smd rect
			(at 3.199892 0 90)
			(size 2.413 2.8194)
			(layers "B.Cu" "B.Mask" "B.Paste")
			(net "PVCCFA_EHV_FIVRA_CPU1")
		)
		(pad "2" smd rect
			(at -3.199892 0 90)
			(size 2.413 2.8194)
			(layers "B.Cu" "B.Mask" "B.Paste")
			(net "GND")
		)
	)
	(footprint ""
		(layer "B.Cu")
		(at 190.25108 -18.938748 180)
		(property "Reference" "R1801"
			(at 0 0 0)
			(layer "B.SilkS")
			(hide yes)
			(effects
				(font
					(size 1.27 1.27)
				)
				(justify mirror)
			)
		)
		(property "Value" ""
			(at 0 0 0)
			(layer "B.Fab")
			(effects
				(font
					(size 1.27 1.27)
				)
				(justify mirror)
			)
		)
		(duplicate_pad_numbers_are_jumpers no)
		(fp_line
			(start 0.7874 0.4064)
			(end 0.7874 -0.4064)
			(stroke
				(width 0.1524)
				(type default)
			)
			(layer "B.SilkS")
		)
		(fp_line
			(start 0.7874 -0.4064)
			(end -0.7874 -0.4064)
			(stroke
				(width 0.1524)
				(type default)
			)
			(layer "B.SilkS")
		)
		(fp_line
			(start -0.7874 0.4064)
			(end 0.7874 0.4064)
			(stroke
				(width 0.1524)
				(type default)
			)
			(layer "B.SilkS")
		)
		(fp_line
			(start -0.7874 -0.4064)
			(end -0.7874 0.4064)
			(stroke
				(width 0.1524)
				(type default)
			)
			(layer "B.SilkS")
		)
		(fp_line
			(start 0.67945 0.3048)
			(end 0.67945 -0.305054)
			(stroke
				(width 0.1)
				(type default)
			)
			(layer "B.Fab")
		)
		(fp_line
			(start 0.67945 -0.305054)
			(end 0.12065 -0.305054)
			(stroke
				(width 0.1)
				(type default)
			)
			(layer "B.Fab")
		)
		(fp_line
			(start 0.12065 0.3048)
			(end 0.67945 0.3048)
			(stroke
				(width 0.1)
				(type default)
			)
			(layer "B.Fab")
		)
		(fp_line
			(start 0.12065 0.2794)
			(end 0.12065 0.3048)
			(stroke
				(width 0.1)
				(type default)
			)
			(layer "B.Fab")
		)
		(fp_line
			(start 0.12065 -0.2794)
			(end -0.12065 -0.2794)
			(stroke
				(width 0.1)
				(type default)
			)
			(layer "B.Fab")
		)
		(fp_line
			(start 0.12065 -0.305054)
			(end 0.12065 -0.2794)
			(stroke
				(width 0.1)
				(type default)
			)
			(layer "B.Fab")
		)
		(fp_line
			(start -0.120396 0.3048)
			(end -0.120396 0.2794)
			(stroke
				(width 0.1)
				(type default)
			)
			(layer "B.Fab")
		)
		(fp_line
			(start -0.120396 0.2794)
			(end 0.12065 0.2794)
			(stroke
				(width 0.1)
				(type default)
			)
			(layer "B.Fab")
		)
		(fp_line
			(start -0.12065 -0.2794)
			(end -0.12065 -0.3048)
			(stroke
				(width 0.1)
				(type default)
			)
			(layer "B.Fab")
		)
		(fp_line
			(start -0.12065 -0.3048)
			(end -0.67945 -0.3048)
			(stroke
				(width 0.1)
				(type default)
			)
			(layer "B.Fab")
		)
		(fp_line
			(start -0.67945 0.3048)
			(end -0.120396 0.3048)
			(stroke
				(width 0.1)
				(type default)
			)
			(layer "B.Fab")
		)
		(fp_line
			(start -0.67945 -0.3048)
			(end -0.67945 0.3048)
			(stroke
				(width 0.1)
				(type default)
			)
			(layer "B.Fab")
		)
		(pad "1" smd circle
			(at 0.40005 0)
			(size 0 0)
			(layers "B.Cu" "B.Mask" "B.Paste")
			(net "PRSNT0_N")
		)
		(pad "2" smd circle
			(at -0.40005 0)
			(size 0 0)
			(layers "B.Cu" "B.Mask" "B.Paste")
			(net "GND")
		)
	)
	(footprint ""
		(layer "B.Cu")
		(at 275.157184 -193.669666 -90)
		(property "Reference" "R250"
			(at 0 0 90)
			(layer "B.SilkS")
			(hide yes)
			(effects
				(font
					(size 1.27 1.27)
				)
				(justify mirror)
			)
		)
		(property "Value" ""
			(at 0 0 90)
			(layer "B.Fab")
			(effects
				(font
					(size 1.27 1.27)
				)
				(justify mirror)
			)
		)
		(duplicate_pad_numbers_are_jumpers no)
		(fp_line
			(start -0.7874 0.4064)
			(end 0.7874 0.4064)
			(stroke
				(width 0.1524)
				(type default)
			)
			(layer "B.SilkS")
		)
		(fp_line
			(start 0.7874 0.4064)
			(end 0.7874 -0.4064)
			(stroke
				(width 0.1524)
				(type default)
			)
			(layer "B.SilkS")
		)
		(fp_line
			(start -0.7874 -0.4064)
			(end -0.7874 0.4064)
			(stroke
				(width 0.1524)
				(type default)
			)
			(layer "B.SilkS")
		)
		(fp_line
			(start 0.7874 -0.4064)
			(end -0.7874 -0.4064)
			(stroke
				(width 0.1524)
				(type default)
			)
			(layer "B.SilkS")
		)
		(fp_line
			(start -0.67945 0.3048)
			(end -0.120396 0.3048)
			(stroke
				(width 0.1)
				(type default)
			)
			(layer "B.Fab")
		)
		(fp_line
			(start -0.120396 0.3048)
			(end -0.120396 0.2794)
			(stroke
				(width 0.1)
				(type default)
			)
			(layer "B.Fab")
		)
		(fp_line
			(start 0.12065 0.3048)
			(end 0.67945 0.3048)
			(stroke
				(width 0.1)
				(type default)
			)
			(layer "B.Fab")
		)
		(fp_line
			(start 0.67945 0.3048)
			(end 0.67945 -0.305054)
			(stroke
				(width 0.1)
				(type default)
			)
			(layer "B.Fab")
		)
		(fp_line
			(start -0.120396 0.2794)
			(end 0.12065 0.2794)
			(stroke
				(width 0.1)
				(type default)
			)
			(layer "B.Fab")
		)
		(fp_line
			(start 0.12065 0.2794)
			(end 0.12065 0.3048)
			(stroke
				(width 0.1)
				(type default)
			)
			(layer "B.Fab")
		)
		(fp_line
			(start -0.12065 -0.2794)
			(end -0.12065 -0.3048)
			(stroke
				(width 0.1)
				(type default)
			)
			(layer "B.Fab")
		)
		(fp_line
			(start 0.12065 -0.2794)
			(end -0.12065 -0.2794)
			(stroke
				(width 0.1)
				(type default)
			)
			(layer "B.Fab")
		)
		(fp_line
			(start -0.67945 -0.3048)
			(end -0.67945 0.3048)
			(stroke
				(width 0.1)
				(type default)
			)
			(layer "B.Fab")
		)
		(fp_line
			(start -0.12065 -0.3048)
			(end -0.67945 -0.3048)
			(stroke
				(width 0.1)
				(type default)
			)
			(layer "B.Fab")
		)
		(fp_line
			(start 0.12065 -0.305054)
			(end 0.12065 -0.2794)
			(stroke
				(width 0.1)
				(type default)
			)
			(layer "B.Fab")
		)
		(fp_line
			(start 0.67945 -0.305054)
			(end 0.12065 -0.305054)
			(stroke
				(width 0.1)
				(type default)
			)
			(layer "B.Fab")
		)
		(pad "1" smd circle
			(at 0.40005 0 90)
			(size 0 0)
			(layers "B.Cu" "B.Mask" "B.Paste")
			(net "PVNN_TERM_CPU0")
		)
		(pad "2" smd circle
			(at -0.40005 0 90)
			(size 0 0)
			(layers "B.Cu" "B.Mask" "B.Paste")
			(net "FM_S3M_CPU0_LVC1_GPIO_1")
		)
	)
	(footprint ""
		(layer "B.Cu")
		(at 324.35292 -331.626718 90)
		(property "Reference" "PR531"
			(at 0 0 90)
			(layer "B.SilkS")
			(hide yes)
			(effects
				(font
					(size 1.27 1.27)
				)
				(justify mirror)
			)
		)
		(property "Value" ""
			(at 0 0 90)
			(layer "B.Fab")
			(effects
				(font
					(size 1.27 1.27)
				)
				(justify mirror)
			)
		)
		(duplicate_pad_numbers_are_jumpers no)
		(fp_line
			(start 0.7874 -0.4064)
			(end -0.7874 -0.4064)
			(stroke
				(width 0.1524)
				(type default)
			)
			(layer "B.SilkS")
		)
		(fp_line
			(start -0.7874 -0.4064)
			(end -0.7874 0.4064)
			(stroke
				(width 0.1524)
				(type default)
			)
			(layer "B.SilkS")
		)
		(fp_line
			(start 0.7874 0.4064)
			(end 0.7874 -0.4064)
			(stroke
				(width 0.1524)
				(type default)
			)
			(layer "B.SilkS")
		)
		(fp_line
			(start -0.7874 0.4064)
			(end 0.7874 0.4064)
			(stroke
				(width 0.1524)
				(type default)
			)
			(layer "B.SilkS")
		)
		(fp_line
			(start 0.67945 -0.305054)
			(end 0.12065 -0.305054)
			(stroke
				(width 0.1)
				(type default)
			)
			(layer "B.Fab")
		)
		(fp_line
			(start 0.12065 -0.305054)
			(end 0.12065 -0.2794)
			(stroke
				(width 0.1)
				(type default)
			)
			(layer "B.Fab")
		)
		(fp_line
			(start -0.12065 -0.3048)
			(end -0.67945 -0.3048)
			(stroke
				(width 0.1)
				(type default)
			)
			(layer "B.Fab")
		)
		(fp_line
			(start -0.67945 -0.3048)
			(end -0.67945 0.3048)
			(stroke
				(width 0.1)
				(type default)
			)
			(layer "B.Fab")
		)
		(fp_line
			(start 0.12065 -0.2794)
			(end -0.12065 -0.2794)
			(stroke
				(width 0.1)
				(type default)
			)
			(layer "B.Fab")
		)
		(fp_line
			(start -0.12065 -0.2794)
			(end -0.12065 -0.3048)
			(stroke
				(width 0.1)
				(type default)
			)
			(layer "B.Fab")
		)
		(fp_line
			(start 0.12065 0.2794)
			(end 0.12065 0.3048)
			(stroke
				(width 0.1)
				(type default)
			)
			(layer "B.Fab")
		)
		(fp_line
			(start -0.120396 0.2794)
			(end 0.12065 0.2794)
			(stroke
				(width 0.1)
				(type default)
			)
			(layer "B.Fab")
		)
		(fp_line
			(start 0.67945 0.3048)
			(end 0.67945 -0.305054)
			(stroke
				(width 0.1)
				(type default)
			)
			(layer "B.Fab")
		)
		(fp_line
			(start 0.12065 0.3048)
			(end 0.67945 0.3048)
			(stroke
				(width 0.1)
				(type default)
			)
			(layer "B.Fab")
		)
		(fp_line
			(start -0.120396 0.3048)
			(end -0.120396 0.2794)
			(stroke
				(width 0.1)
				(type default)
			)
			(layer "B.Fab")
		)
		(fp_line
			(start -0.67945 0.3048)
			(end -0.120396 0.3048)
			(stroke
				(width 0.1)
				(type default)
			)
			(layer "B.Fab")
		)
		(pad "1" smd circle
			(at 0.40005 0 270)
			(size 0 0)
			(layers "B.Cu" "B.Mask" "B.Paste")
			(net "VSENSE_PVCCIN_CPU0_DP")
		)
		(pad "2" smd circle
			(at -0.40005 0 270)
			(size 0 0)
			(layers "B.Cu" "B.Mask" "B.Paste")
			(net "PVCCIN_CPU0")
		)
	)
	(footprint ""
		(layer "B.Cu")
		(at 291.004498 -403.031452 90)
		(property "Reference" "PR2511"
			(at 0 0 90)
			(layer "B.SilkS")
			(hide yes)
			(effects
				(font
					(size 1.27 1.27)
				)
				(justify mirror)
			)
		)
		(property "Value" ""
			(at 0 0 90)
			(layer "B.Fab")
			(effects
				(font
					(size 1.27 1.27)
				)
				(justify mirror)
			)
		)
		(duplicate_pad_numbers_are_jumpers no)
		(fp_line
			(start 0.7874 -0.4064)
			(end -0.7874 -0.4064)
			(stroke
				(width 0.1524)
				(type default)
			)
			(layer "B.SilkS")
		)
		(fp_line
			(start -0.7874 -0.4064)
			(end -0.7874 0.4064)
			(stroke
				(width 0.1524)
				(type default)
			)
			(layer "B.SilkS")
		)
		(fp_line
			(start 0.7874 0.4064)
			(end 0.7874 -0.4064)
			(stroke
				(width 0.1524)
				(type default)
			)
			(layer "B.SilkS")
		)
		(fp_line
			(start -0.7874 0.4064)
			(end 0.7874 0.4064)
			(stroke
				(width 0.1524)
				(type default)
			)
			(layer "B.SilkS")
		)
		(fp_line
			(start 0.67945 -0.305054)
			(end 0.12065 -0.305054)
			(stroke
				(width 0.1)
				(type default)
			)
			(layer "B.Fab")
		)
		(fp_line
			(start 0.12065 -0.305054)
			(end 0.12065 -0.2794)
			(stroke
				(width 0.1)
				(type default)
			)
			(layer "B.Fab")
		)
		(fp_line
			(start -0.12065 -0.3048)
			(end -0.67945 -0.3048)
			(stroke
				(width 0.1)
				(type default)
			)
			(layer "B.Fab")
		)
		(fp_line
			(start -0.67945 -0.3048)
			(end -0.67945 0.3048)
			(stroke
				(width 0.1)
				(type default)
			)
			(layer "B.Fab")
		)
		(fp_line
			(start 0.12065 -0.2794)
			(end -0.12065 -0.2794)
			(stroke
				(width 0.1)
				(type default)
			)
			(layer "B.Fab")
		)
		(fp_line
			(start -0.12065 -0.2794)
			(end -0.12065 -0.3048)
			(stroke
				(width 0.1)
				(type default)
			)
			(layer "B.Fab")
		)
		(fp_line
			(start 0.12065 0.2794)
			(end 0.12065 0.3048)
			(stroke
				(width 0.1)
				(type default)
			)
			(layer "B.Fab")
		)
		(fp_line
			(start -0.120396 0.2794)
			(end 0.12065 0.2794)
			(stroke
				(width 0.1)
				(type default)
			)
			(layer "B.Fab")
		)
		(fp_line
			(start 0.67945 0.3048)
			(end 0.67945 -0.305054)
			(stroke
				(width 0.1)
				(type default)
			)
			(layer "B.Fab")
		)
		(fp_line
			(start 0.12065 0.3048)
			(end 0.67945 0.3048)
			(stroke
				(width 0.1)
				(type default)
			)
			(layer "B.Fab")
		)
		(fp_line
			(start -0.120396 0.3048)
			(end -0.120396 0.2794)
			(stroke
				(width 0.1)
				(type default)
			)
			(layer "B.Fab")
		)
		(fp_line
			(start -0.67945 0.3048)
			(end -0.120396 0.3048)
			(stroke
				(width 0.1)
				(type default)
			)
			(layer "B.Fab")
		)
		(pad "1" smd circle
			(at 0.40005 0 270)
			(size 0 0)
			(layers "B.Cu" "B.Mask" "B.Paste")
			(net "P12V_HSC_ADC_P")
		)
		(pad "2" smd circle
			(at -0.40005 0 270)
			(size 0 0)
			(layers "B.Cu" "B.Mask" "B.Paste")
			(net "P12V_HSC_SENSE2_R2_P")
		)
	)
)
